# BASEBOARD_FAB2 (Tioga Pass) — schematic netlist excerpt (pin names and nets, part order shuffled) for the footprints in the layout excerpt that follows; sources: Cadence DE-HDL packaged netlist, KiCad conversion of Wiwynn_Tioga_Pass_MB.brd

C7G19  CAP  0.22UF 16V 10% X7R  pkg 0402  page 105 : A = P3E_CPU0_PE2_SS_TXN<8> ; B = P3E_CPU0_PE2_SS_C_TXN<8>
CF21  SC22P50V2JN-4GP  5%  pkg SMD-BCG  page 226 : \1\ = VR_PVDDQ_KLM_AIREF1 ; \2\ = ISENSE_PVDDQ_KLM_PH1_IMON
C5D44  CAP_A  22.0UF 4V 20% X6S  pkg 0603V  page 42 : A = PVCCIN_CPU0 ; B = GND

(kicad_pcb
	(version 20260206)
	(generator "pcbnew")
	(generator_version "10.0")
	(general
		(thickness 1.6)
		(legacy_teardrops no)
	)
	(paper "A4")
	(title_block
		(title "Wiwynn_Tioga_Pass_MB.brd")
		(comment 1 "Tioga Pass / footprints 2142-2144 of 4770")
	)
	(layers
		(0 "F.Cu" signal "TOP")
		(4 "In1.Cu" signal "L2GND")
		(6 "In2.Cu" signal "L3")
		(8 "In3.Cu" signal "L4GND")
		(10 "In4.Cu" signal "L5")
		(12 "In5.Cu" signal "L6GND")
		(14 "In6.Cu" signal "L7VCC")
		(16 "In7.Cu" signal "L8VCC")
		(18 "In8.Cu" signal "L9GND")
		(20 "In9.Cu" signal "L10")
		(22 "In10.Cu" signal "L11GND")
		(24 "In11.Cu" signal "L12")
		(26 "In12.Cu" signal "L13GND")
		(2 "B.Cu" signal "BOTTOM")
		(9 "F.Adhes" user "F.Adhesive")
		(11 "B.Adhes" user "B.Adhesive")
		(13 "F.Paste" user "Package Geometry/Pastemask Top")
		(15 "B.Paste" user "Package Geometry/Pastemask Bottom")
		(5 "F.SilkS" user "Ref Des/Silkscreen Top")
		(7 "B.SilkS" user "Ref Des/Silkscreen Bottom")
		(1 "F.Mask" user "Board Geometry/Soldermask Top")
		(3 "B.Mask" user "Board Geometry/Soldermask Bottom")
		(17 "Dwgs.User" user "User.Drawings")
		(19 "Cmts.User" user "User.Comments")
		(21 "Eco1.User" user "User.Eco1")
		(23 "Eco2.User" user "User.Eco2")
		(25 "Edge.Cuts" user "Board Geometry/Outline")
		(27 "Margin" user)
		(31 "F.CrtYd" user "Package Geometry/Place Bound Top")
		(29 "B.CrtYd" user "Package Geometry/Place Bound Bottom")
		(35 "F.Fab" user "Ref Des/Assembly Top")
		(33 "B.Fab" user "Ref Des/Assembly Bottom")
	)
	(footprint ""
		(layer "F.Cu")
		(at -0.786384 -123.210574 90)
		(property "Reference" "CF21"
			(at 0 0 90)
			(layer "F.SilkS")
			(hide yes)
			(effects
				(font
					(size 1.27 1.27)
				)
			)
		)
		(property "Value" "*"
			(at 1.1811 -2.8194 90)
			(unlocked yes)
			(layer "F.Fab")
			(hide yes)
			(effects
				(font
					(size 1.27 1.016)
					(thickness 0.1524)
				)
			)
		)
		(property "Device Type" "SC22P50V2JN-4GP_SMD-BCG-SC22P5A"
			(at 1.1811 -4.3434 90)
			(unlocked yes)
			(layer "F.Fab")
			(hide yes)
			(effects
				(font
					(size 1.27 1.016)
					(thickness 0.1524)
				)
			)
		)
		(duplicate_pad_numbers_are_jumpers no)
		(fp_rect
			(start -0.4318 0.9525)
			(end 0.4318 -0.9525)
			(stroke
				(width 0)
				(type default)
			)
			(fill no)
			(layer "F.CrtYd")
		)
		(fp_rect
			(start -0.4318 0.9525)
			(end 0.4318 -0.9525)
			(stroke
				(width 0)
				(type default)
			)
			(fill no)
			(layer "F.Fab")
		)
		(pad "1" smd custom
			(at 0 -0.4445 90)
			(size 0.1524 0.1524)
			(layers "F.Cu" "F.Mask" "F.Paste")
			(net "VR_PVDDQ_KLM_AIREF1")
			(options
				(clearance outline)
				(anchor circle)
			)
			(primitives
				(gr_poly
					(pts
						(arc
							(start 0.3048 -0.2032)
							(mid 0.275042 -0.275042)
							(end 0.2032 -0.3048)
						)
						(arc
							(start -0.2032 -0.3048)
							(mid -0.275042 -0.275042)
							(end -0.3048 -0.2032)
						)
						(arc
							(start -0.3048 0.2032)
							(mid -0.275042 0.275042)
							(end -0.2032 0.3048)
						)
						(arc
							(start 0.2032 0.3048)
							(mid 0.275042 0.275042)
							(end 0.3048 0.2032)
						)
					)
					(width 0)
					(fill yes)
				)
			)
		)
		(pad "2" smd custom
			(at 0 0.4445 90)
			(size 0.1524 0.1524)
			(layers "F.Cu" "F.Mask" "F.Paste")
			(net "ISENSE_PVDDQ_KLM_PH1_IMON")
			(options
				(clearance outline)
				(anchor circle)
			)
			(primitives
				(gr_poly
					(pts
						(arc
							(start 0.3048 -0.2032)
							(mid 0.275042 -0.275042)
							(end 0.2032 -0.3048)
						)
						(arc
							(start -0.2032 -0.3048)
							(mid -0.275042 -0.275042)
							(end -0.3048 -0.2032)
						)
						(arc
							(start -0.3048 0.2032)
							(mid -0.275042 0.275042)
							(end -0.2032 0.3048)
						)
						(arc
							(start 0.2032 0.3048)
							(mid 0.275042 0.275042)
							(end 0.3048 0.2032)
						)
					)
					(width 0)
					(fill yes)
				)
			)
		)
	)
	(footprint ""
		(layer "F.Cu")
		(at 264.431272 -73.318116)
		(property "Reference" "C5D44"
			(at 0 0 0)
			(layer "F.SilkS")
			(hide yes)
			(effects
				(font
					(size 1.27 1.27)
				)
			)
		)
		(property "Value" ""
			(at 0 0 0)
			(layer "F.Fab")
			(effects
				(font
					(size 1.27 1.27)
				)
			)
		)
		(duplicate_pad_numbers_are_jumpers no)
		(fp_poly
			(pts
				(xy -0.4953 -0.2032) (xy 0.4953 -0.2032) (xy 0.4953 1.6002) (xy -0.4953 1.6002)
			)
			(stroke
				(width 0)
				(type default)
			)
			(fill no)
			(layer "F.CrtYd")
		)
		(fp_line
			(start -0.4953 -0.2032)
			(end 0.4953 -0.2032)
			(stroke
				(width 0.1)
				(type default)
			)
			(layer "F.Fab")
		)
		(fp_line
			(start -0.4953 1.6002)
			(end -0.4953 -0.2032)
			(stroke
				(width 0.1)
				(type default)
			)
			(layer "F.Fab")
		)
		(fp_line
			(start 0.4953 -0.2032)
			(end 0.4953 1.6002)
			(stroke
				(width 0.1)
				(type default)
			)
			(layer "F.Fab")
		)
		(fp_line
			(start 0.4953 1.6002)
			(end -0.4953 1.6002)
			(stroke
				(width 0.1)
				(type default)
			)
			(layer "F.Fab")
		)
		(pad "1" smd rect
			(at 0 0)
			(size 0.762 0.889)
			(layers "F.Cu" "F.Mask" "F.Paste")
			(net "PVCCIN_CPU0")
		)
		(pad "2" smd rect
			(at 0 1.397)
			(size 0.762 0.889)
			(layers "F.Cu" "F.Mask" "F.Paste")
			(net "GND")
		)
		(zone
			(layer "F.Cu")
			(hatch none 0.5)
			(connect_pads
				(clearance 0)
			)
			(min_thickness 0.25)
			(keepout
				(tracks not_allowed)
				(vias allowed)
				(pads allowed)
				(copperpour not_allowed)
				(footprints allowed)
			)
			(placement
				(enabled no)
				(sheetname "")
			)
			(fill
				(thermal_gap 0.5)
				(thermal_bridge_width 0.5)
				(island_removal_mode 0)
			)
			(polygon
				(pts
					(xy 264.050272 -72.873616) (xy 264.812272 -72.873616) (xy 264.812272 -72.365616) (xy 264.050272 -72.365616)
				)
			)
		)
	)
	(footprint ""
		(layer "F.Cu")
		(at 379.815344 -10.941558)
		(property "Reference" "C7G19"
			(at 0 0 0)
			(layer "F.SilkS")
			(hide yes)
			(effects
				(font
					(size 1.27 1.27)
				)
			)
		)
		(property "Value" ""
			(at 0 0 0)
			(layer "F.Fab")
			(effects
				(font
					(size 1.27 1.27)
				)
			)
		)
		(duplicate_pad_numbers_are_jumpers no)
		(fp_rect
			(start -0.3048 0.9906)
			(end 0.3048 -0.1016)
			(stroke
				(width 0)
				(type default)
			)
			(fill no)
			(layer "F.CrtYd")
		)
		(fp_line
			(start -0.3048 -0.1016)
			(end -0.3048 0.9906)
			(stroke
				(width 0.1)
				(type default)
			)
			(layer "F.Fab")
		)
		(fp_line
			(start -0.3048 0.9906)
			(end 0.3048 0.9906)
			(stroke
				(width 0.1)
				(type default)
			)
			(layer "F.Fab")
		)
		(fp_line
			(start 0.3048 -0.1016)
			(end -0.3048 -0.1016)
			(stroke
				(width 0.1)
				(type default)
			)
			(layer "F.Fab")
		)
		(fp_line
			(start 0.3048 0.9906)
			(end 0.3048 -0.1016)
			(stroke
				(width 0.1)
				(type default)
			)
			(layer "F.Fab")
		)
		(pad "1" smd rect
			(at 0 0)
			(size 0.508 0.508)
			(layers "F.Cu" "F.Mask" "F.Paste")
			(net "P3E_CPU0_PE2_SS_TXN<8>")
		)
		(pad "2" smd rect
			(at 0 0.889)
			(size 0.508 0.508)
			(layers "F.Cu" "F.Mask" "F.Paste")
			(net "P3E_CPU0_PE2_SS_C_TXN<8>")
		)
		(zone
			(layer "F.Cu")
			(hatch none 0.5)
			(connect_pads
				(clearance 0)
			)
			(min_thickness 0.25)
			(keepout
				(tracks not_allowed)
				(vias allowed)
				(pads allowed)
				(copperpour not_allowed)
				(footprints allowed)
			)
			(placement
				(enabled no)
				(sheetname "")
			)
			(fill
				(thermal_gap 0.5)
				(thermal_bridge_width 0.5)
				(island_removal_mode 0)
			)
			(polygon
				(pts
					(xy 379.561344 -10.306558) (xy 380.069344 -10.306558) (xy 380.069344 -10.687558) (xy 379.561344 -10.687558)
				)
			)
		)
		(zone
			(layer "F.Cu")
			(hatch none 0.5)
			(connect_pads
				(clearance 0)
			)
			(min_thickness 0.25)
			(keepout
				(tracks allowed)
				(vias not_allowed)
				(pads allowed)
				(copperpour not_allowed)
				(footprints allowed)
			)
			(placement
				(enabled no)
				(sheetname "")
			)
			(fill
				(thermal_gap 0.5)
				(thermal_bridge_width 0.5)
				(island_removal_mode 0)
			)
			(polygon
				(pts
					(xy 379.561344 -10.306558) (xy 380.069344 -10.306558) (xy 380.069344 -10.687558) (xy 379.561344 -10.687558)
				)
			)
		)
	)
)
